#ISCELL
  pure_quanta quanta_title_block_c *
  *
#ISCELL
  standard offpage *
  page464_i1
#ISCELL
  pure_quanta_power p1v0 *
  page464_i18
#CELL
  pure_quanta q_cap *
  page464_i19
#ISCELL
  standard offpage *
  page464_i2
#ISCELL
  pure_quanta_power universal_gnd *
  page464_i20
#ISCELL
  pure_quanta_power universal_gnd *
  page464_i21
#CELL
  pure_quanta q_res *
  page464_i22
#ISCELL
  pure_quanta_power universal_gnd *
  page464_i23
#ISCELL
  pure_quanta_power universal_gnd *
  page464_i24
#CELL
  pure_quanta q_res *
  page464_i25
#CELL
  pure_quanta q_res *
  page464_i4
#CELL
  pure_quanta m24m02drmn6tp *
  page464_i5
